(kicad_pcb
	(version 20260206)
	(generator "pcbnew")
	(generator_version "10.0")
	(general
		(thickness 1.6)
		(legacy_teardrops no)
	)
	(paper "A4")
	(title_block
		(title "pdpb — Lightning_PDPB_BRD.brd")
		(comment 1 "Lightning (Wiwynn / Facebook NVMe JBOF) / footprints 960-966 of 1140")
	)
	(layers
		(0 "F.Cu" signal "TOP")
		(4 "In1.Cu" signal "L2GND")
		(6 "In2.Cu" signal "L3")
		(8 "In3.Cu" signal "L4VCC")
		(10 "In4.Cu" signal "L5VCC")
		(12 "In5.Cu" signal "L6")
		(14 "In6.Cu" signal "L7GND")
		(2 "B.Cu" signal "BOTTOM")
		(9 "F.Adhes" user "F.Adhesive")
		(11 "B.Adhes" user "B.Adhesive")
		(13 "F.Paste" user "Package Geometry/Pastemask Top")
		(15 "B.Paste" user "Package Geometry/Pastemask Bottom")
		(5 "F.SilkS" user "Ref Des/Silkscreen Top")
		(7 "B.SilkS" user "Ref Des/Silkscreen Bottom")
		(1 "F.Mask" user "Board Geometry/Soldermask Top")
		(3 "B.Mask" user "Board Geometry/Soldermask Bottom")
		(17 "Dwgs.User" user "User.Drawings")
		(19 "Cmts.User" user "User.Comments")
		(21 "Eco1.User" user "User.Eco1")
		(23 "Eco2.User" user "User.Eco2")
		(25 "Edge.Cuts" user "Board Geometry/Outline")
		(27 "Margin" user)
		(31 "F.CrtYd" user "Package Geometry/Place Bound Top")
		(29 "B.CrtYd" user "Package Geometry/Place Bound Bottom")
		(35 "F.Fab" user "Ref Des/Assembly Top")
		(33 "B.Fab" user "Ref Des/Assembly Bottom")
	)
	(footprint ""
		(layer "F.Cu")
		(at 74.168 -154.178)
		(property "Reference" "SR971"
			(at 0 0 0)
			(layer "F.SilkS")
			(hide yes)
			(effects
				(font
					(size 1.27 1.27)
				)
			)
		)
		(property "Value" "2KR2F-3-GP"
			(at 0.064008 -3.993896 0)
			(unlocked yes)
			(layer "F.Fab")
			(hide yes)
			(effects
				(font
					(size 1.016 1.016)
					(thickness 0.1524)
				)
			)
		)
		(property "Device Type" "R402H16"
			(at 0.064008 -5.517896 0)
			(unlocked yes)
			(layer "F.Fab")
			(hide yes)
			(effects
				(font
					(size 1.016 1.016)
					(thickness 0.1524)
				)
			)
		)
		(duplicate_pad_numbers_are_jumpers no)
		(fp_line
			(start -0.508 -0.9398)
			(end -0.508 0.9398)
			(stroke
				(width 0.1524)
				(type default)
			)
			(layer "F.SilkS")
		)
		(fp_line
			(start 0.508 -0.9398)
			(end -0.508 -0.9398)
			(stroke
				(width 0.1524)
				(type default)
			)
			(layer "F.SilkS")
		)
		(fp_rect
			(start -0.508 0.9398)
			(end 0.508 -0.9398)
			(stroke
				(width 0)
				(type default)
			)
			(fill no)
			(layer "F.CrtYd")
		)
		(fp_rect
			(start -0.508 0.9398)
			(end 0.508 -0.9398)
			(stroke
				(width 0)
				(type default)
			)
			(fill no)
			(layer "F.Fab")
		)
		(pad "1" smd custom
			(at 0 -0.4445)
			(size 0.1397 0.1397)
			(layers "F.Cu" "F.Mask" "F.Paste")
			(net "P3V3")
			(options
				(clearance outline)
				(anchor circle)
			)
			(primitives
				(gr_poly
					(pts
						(arc
							(start -0.1778 -0.2794)
							(mid -0.249642 -0.249642)
							(end -0.2794 -0.1778)
						)
						(arc
							(start -0.2794 0.1778)
							(mid -0.249642 0.249642)
							(end -0.1778 0.2794)
						)
						(arc
							(start 0.1778 0.2794)
							(mid 0.249642 0.249642)
							(end 0.2794 0.1778)
						)
						(arc
							(start 0.2794 -0.1778)
							(mid 0.249642 -0.249642)
							(end 0.1778 -0.2794)
						)
					)
					(width 0)
					(fill yes)
				)
			)
		)
		(pad "2" smd custom
			(at 0 0.4445)
			(size 0.1397 0.1397)
			(layers "F.Cu" "F.Mask" "F.Paste")
			(net "SDA_DR12")
			(options
				(clearance outline)
				(anchor circle)
			)
			(primitives
				(gr_poly
					(pts
						(arc
							(start -0.1778 -0.2794)
							(mid -0.249642 -0.249642)
							(end -0.2794 -0.1778)
						)
						(arc
							(start -0.2794 0.1778)
							(mid -0.249642 0.249642)
							(end -0.1778 0.2794)
						)
						(arc
							(start 0.1778 0.2794)
							(mid 0.249642 0.249642)
							(end 0.2794 0.1778)
						)
						(arc
							(start 0.2794 -0.1778)
							(mid 0.249642 -0.249642)
							(end 0.1778 -0.2794)
						)
					)
					(width 0)
					(fill yes)
				)
			)
		)
	)
	(footprint ""
		(layer "F.Cu")
		(at 6.7564 -378.4854 180)
		(property "Reference" "C9534"
			(at 0 0 180)
			(layer "F.SilkS")
			(hide yes)
			(effects
				(font
					(size 1.27 1.27)
				)
			)
		)
		(property "Value" "SCD01U50V2KX-1GP"
			(at 1.1811 -2.7051 180)
			(unlocked yes)
			(layer "F.Fab")
			(hide yes)
			(effects
				(font
					(size 1.016 1.016)
					(thickness 0.1524)
				)
			)
		)
		(property "Device Type" "C402H22"
			(at 1.1811 -4.2291 180)
			(unlocked yes)
			(layer "F.Fab")
			(hide yes)
			(effects
				(font
					(size 1.016 1.016)
					(thickness 0.1524)
				)
			)
		)
		(duplicate_pad_numbers_are_jumpers no)
		(fp_rect
			(start -0.4318 0.9525)
			(end 0.4318 -0.9525)
			(stroke
				(width 0)
				(type default)
			)
			(fill no)
			(layer "F.CrtYd")
		)
		(fp_rect
			(start -0.4318 0.9525)
			(end 0.4318 -0.9525)
			(stroke
				(width 0)
				(type default)
			)
			(fill no)
			(layer "F.Fab")
		)
		(pad "1" smd custom
			(at 0 -0.4445 180)
			(size 0.1524 0.1524)
			(layers "F.Cu" "F.Mask" "F.Paste")
			(net "PE_100M_CLK1_N")
			(options
				(clearance outline)
				(anchor circle)
			)
			(primitives
				(gr_poly
					(pts
						(arc
							(start 0.3048 -0.2032)
							(mid 0.275042 -0.275042)
							(end 0.2032 -0.3048)
						)
						(arc
							(start -0.2032 -0.3048)
							(mid -0.275042 -0.275042)
							(end -0.3048 -0.2032)
						)
						(arc
							(start -0.3048 0.2032)
							(mid -0.275042 0.275042)
							(end -0.2032 0.3048)
						)
						(arc
							(start 0.2032 0.3048)
							(mid 0.275042 0.275042)
							(end 0.3048 0.2032)
						)
					)
					(width 0)
					(fill yes)
				)
			)
		)
		(pad "2" smd custom
			(at 0 0.4445 180)
			(size 0.1524 0.1524)
			(layers "F.Cu" "F.Mask" "F.Paste")
			(net "PE_100M_CLK1_C_N")
			(options
				(clearance outline)
				(anchor circle)
			)
			(primitives
				(gr_poly
					(pts
						(arc
							(start 0.3048 -0.2032)
							(mid 0.275042 -0.275042)
							(end 0.2032 -0.3048)
						)
						(arc
							(start -0.2032 -0.3048)
							(mid -0.275042 -0.275042)
							(end -0.3048 -0.2032)
						)
						(arc
							(start -0.3048 0.2032)
							(mid -0.275042 0.275042)
							(end -0.2032 0.3048)
						)
						(arc
							(start 0.2032 0.3048)
							(mid 0.275042 0.275042)
							(end 0.3048 0.2032)
						)
					)
					(width 0)
					(fill yes)
				)
			)
		)
	)
	(footprint ""
		(layer "F.Cu")
		(at 36.576 -474.218 180)
		(property "Reference" "PC1209"
			(at 0 0 180)
			(layer "F.SilkS")
			(hide yes)
			(effects
				(font
					(size 1.27 1.27)
				)
			)
		)
		(property "Value" "SCD1U25V3KX-GP"
			(at 0 -2.8194 180)
			(unlocked yes)
			(layer "F.Fab")
			(hide yes)
			(effects
				(font
					(size 1.016 1.016)
					(thickness 0.1524)
				)
			)
		)
		(property "Device Type" "C603H36"
			(at 0 -4.3434 180)
			(unlocked yes)
			(layer "F.Fab")
			(hide yes)
			(effects
				(font
					(size 1.016 1.016)
					(thickness 0.1524)
				)
			)
		)
		(duplicate_pad_numbers_are_jumpers no)
		(fp_line
			(start 0.508 0)
			(end -0.508 0)
			(stroke
				(width 0.2032)
				(type default)
			)
			(layer "F.SilkS")
		)
		(fp_rect
			(start -0.5842 1.3335)
			(end 0.5842 -1.3335)
			(stroke
				(width 0)
				(type default)
			)
			(fill no)
			(layer "F.CrtYd")
		)
		(fp_rect
			(start -0.5842 1.3335)
			(end 0.5842 -1.3335)
			(stroke
				(width 0)
				(type default)
			)
			(fill no)
			(layer "F.Fab")
		)
		(pad "1" smd custom
			(at 0 -0.762 180)
			(size 0.2159 0.2159)
			(layers "F.Cu" "F.Mask" "F.Paste")
			(net "P3V3")
			(options
				(clearance outline)
				(anchor circle)
			)
			(primitives
				(gr_poly
					(pts
						(arc
							(start -0.3302 -0.4318)
							(mid -0.402042 -0.402042)
							(end -0.4318 -0.3302)
						)
						(arc
							(start -0.4318 0.3302)
							(mid -0.402042 0.402042)
							(end -0.3302 0.4318)
						)
						(arc
							(start 0.3302 0.4318)
							(mid 0.402042 0.402042)
							(end 0.4318 0.3302)
						)
						(arc
							(start 0.4318 -0.3302)
							(mid 0.402042 -0.402042)
							(end 0.3302 -0.4318)
						)
					)
					(width 0)
					(fill yes)
				)
			)
		)
		(pad "2" smd custom
			(at 0 0.762 180)
			(size 0.2159 0.2159)
			(layers "F.Cu" "F.Mask" "F.Paste")
			(net "GND")
			(options
				(clearance outline)
				(anchor circle)
			)
			(primitives
				(gr_poly
					(pts
						(arc
							(start -0.3302 -0.4318)
							(mid -0.402042 -0.402042)
							(end -0.4318 -0.3302)
						)
						(arc
							(start -0.4318 0.3302)
							(mid -0.402042 0.402042)
							(end -0.3302 0.4318)
						)
						(arc
							(start 0.3302 0.4318)
							(mid 0.402042 0.402042)
							(end 0.4318 0.3302)
						)
						(arc
							(start 0.4318 -0.3302)
							(mid 0.402042 -0.402042)
							(end 0.3302 -0.4318)
						)
					)
					(width 0)
					(fill yes)
				)
			)
		)
	)
	(footprint ""
		(layer "F.Cu")
		(at 217.043 -81.534 -90)
		(property "Reference" "R395"
			(at 0 0 270)
			(layer "F.SilkS")
			(hide yes)
			(effects
				(font
					(size 1.27 1.27)
				)
			)
		)
		(property "Value" "0R2J-2-GP"
			(at 0.064008 -3.993896 270)
			(unlocked yes)
			(layer "F.Fab")
			(hide yes)
			(effects
				(font
					(size 1.016 1.016)
					(thickness 0.1524)
				)
			)
		)
		(property "Device Type" "R402H16"
			(at 0.064008 -5.517896 270)
			(unlocked yes)
			(layer "F.Fab")
			(hide yes)
			(effects
				(font
					(size 1.016 1.016)
					(thickness 0.1524)
				)
			)
		)
		(duplicate_pad_numbers_are_jumpers no)
		(fp_line
			(start -0.508 -0.9398)
			(end -0.508 0.9398)
			(stroke
				(width 0.1524)
				(type default)
			)
			(layer "F.SilkS")
		)
		(fp_line
			(start 0.508 -0.9398)
			(end -0.508 -0.9398)
			(stroke
				(width 0.1524)
				(type default)
			)
			(layer "F.SilkS")
		)
		(fp_rect
			(start -0.508 0.9398)
			(end 0.508 -0.9398)
			(stroke
				(width 0)
				(type default)
			)
			(fill no)
			(layer "F.CrtYd")
		)
		(fp_rect
			(start -0.508 0.9398)
			(end 0.508 -0.9398)
			(stroke
				(width 0)
				(type default)
			)
			(fill no)
			(layer "F.Fab")
		)
		(pad "1" smd custom
			(at 0 -0.4445 270)
			(size 0.1397 0.1397)
			(layers "F.Cu" "F.Mask" "F.Paste")
			(net "SCL_DR4_R")
			(options
				(clearance outline)
				(anchor circle)
			)
			(primitives
				(gr_poly
					(pts
						(arc
							(start -0.1778 -0.2794)
							(mid -0.249642 -0.249642)
							(end -0.2794 -0.1778)
						)
						(arc
							(start -0.2794 0.1778)
							(mid -0.249642 0.249642)
							(end -0.1778 0.2794)
						)
						(arc
							(start 0.1778 0.2794)
							(mid 0.249642 0.249642)
							(end 0.2794 0.1778)
						)
						(arc
							(start 0.2794 -0.1778)
							(mid 0.249642 -0.249642)
							(end 0.1778 -0.2794)
						)
					)
					(width 0)
					(fill yes)
				)
			)
		)
		(pad "2" smd custom
			(at 0 0.4445 270)
			(size 0.1397 0.1397)
			(layers "F.Cu" "F.Mask" "F.Paste")
			(net "SCL_DR4")
			(options
				(clearance outline)
				(anchor circle)
			)
			(primitives
				(gr_poly
					(pts
						(arc
							(start -0.1778 -0.2794)
							(mid -0.249642 -0.249642)
							(end -0.2794 -0.1778)
						)
						(arc
							(start -0.2794 0.1778)
							(mid -0.249642 0.249642)
							(end -0.1778 0.2794)
						)
						(arc
							(start 0.1778 0.2794)
							(mid 0.249642 0.249642)
							(end 0.2794 0.1778)
						)
						(arc
							(start 0.2794 -0.1778)
							(mid 0.249642 -0.249642)
							(end 0.1778 -0.2794)
						)
					)
					(width 0)
					(fill yes)
				)
			)
		)
	)
	(footprint ""
		(layer "F.Cu")
		(at 83.185 -149.606 90)
		(property "Reference" "SR1153"
			(at 0 0 90)
			(layer "F.SilkS")
			(hide yes)
			(effects
				(font
					(size 1.27 1.27)
				)
			)
		)
		(property "Value" "4K7R2F-GP"
			(at 0.064008 -3.993896 90)
			(unlocked yes)
			(layer "F.Fab")
			(hide yes)
			(effects
				(font
					(size 1.016 1.016)
					(thickness 0.1524)
				)
			)
		)
		(property "Device Type" "R402H16"
			(at 0.064008 -5.517896 90)
			(unlocked yes)
			(layer "F.Fab")
			(hide yes)
			(effects
				(font
					(size 1.016 1.016)
					(thickness 0.1524)
				)
			)
		)
		(duplicate_pad_numbers_are_jumpers no)
		(fp_line
			(start 0.508 -0.9398)
			(end -0.508 -0.9398)
			(stroke
				(width 0.1524)
				(type default)
			)
			(layer "F.SilkS")
		)
		(fp_line
			(start -0.508 -0.9398)
			(end -0.508 0.9398)
			(stroke
				(width 0.1524)
				(type default)
			)
			(layer "F.SilkS")
		)
		(fp_rect
			(start -0.508 0.9398)
			(end 0.508 -0.9398)
			(stroke
				(width 0)
				(type default)
			)
			(fill no)
			(layer "F.CrtYd")
		)
		(fp_rect
			(start -0.508 0.9398)
			(end 0.508 -0.9398)
			(stroke
				(width 0)
				(type default)
			)
			(fill no)
			(layer "F.Fab")
		)
		(pad "1" smd custom
			(at 0 -0.4445 90)
			(size 0.1397 0.1397)
			(layers "F.Cu" "F.Mask" "F.Paste")
			(net "I2C_SW_EU16_ADDRESS_A0")
			(options
				(clearance outline)
				(anchor circle)
			)
			(primitives
				(gr_poly
					(pts
						(arc
							(start -0.1778 -0.2794)
							(mid -0.249642 -0.249642)
							(end -0.2794 -0.1778)
						)
						(arc
							(start -0.2794 0.1778)
							(mid -0.249642 0.249642)
							(end -0.1778 0.2794)
						)
						(arc
							(start 0.1778 0.2794)
							(mid 0.249642 0.249642)
							(end 0.2794 0.1778)
						)
						(arc
							(start 0.2794 -0.1778)
							(mid 0.249642 -0.249642)
							(end 0.1778 -0.2794)
						)
					)
					(width 0)
					(fill yes)
				)
			)
		)
		(pad "2" smd custom
			(at 0 0.4445 90)
			(size 0.1397 0.1397)
			(layers "F.Cu" "F.Mask" "F.Paste")
			(net "GND")
			(options
				(clearance outline)
				(anchor circle)
			)
			(primitives
				(gr_poly
					(pts
						(arc
							(start -0.1778 -0.2794)
							(mid -0.249642 -0.249642)
							(end -0.2794 -0.1778)
						)
						(arc
							(start -0.2794 0.1778)
							(mid -0.249642 0.249642)
							(end -0.1778 0.2794)
						)
						(arc
							(start 0.1778 0.2794)
							(mid 0.249642 0.249642)
							(end 0.2794 0.1778)
						)
						(arc
							(start 0.2794 -0.1778)
							(mid 0.249642 -0.249642)
							(end 0.1778 -0.2794)
						)
					)
					(width 0)
					(fill yes)
				)
			)
		)
	)
	(footprint ""
		(layer "F.Cu")
		(at 8.7122 -465.3534 90)
		(property "Reference" "PC1163"
			(at 0 0 90)
			(layer "F.SilkS")
			(hide yes)
			(effects
				(font
					(size 1.27 1.27)
				)
			)
		)
		(property "Value" "SCD1U50V3KX-GP"
			(at 0 -2.8194 90)
			(unlocked yes)
			(layer "F.Fab")
			(hide yes)
			(effects
				(font
					(size 1.016 1.016)
					(thickness 0.1524)
				)
			)
		)
		(property "Device Type" "C603H36"
			(at 0 -4.3434 90)
			(unlocked yes)
			(layer "F.Fab")
			(hide yes)
			(effects
				(font
					(size 1.016 1.016)
					(thickness 0.1524)
				)
			)
		)
		(duplicate_pad_numbers_are_jumpers no)
		(fp_line
			(start 0.508 0)
			(end -0.508 0)
			(stroke
				(width 0.2032)
				(type default)
			)
			(layer "F.SilkS")
		)
		(fp_rect
			(start -0.5842 1.3335)
			(end 0.5842 -1.3335)
			(stroke
				(width 0)
				(type default)
			)
			(fill no)
			(layer "F.CrtYd")
		)
		(fp_rect
			(start -0.5842 1.3335)
			(end 0.5842 -1.3335)
			(stroke
				(width 0)
				(type default)
			)
			(fill no)
			(layer "F.Fab")
		)
		(pad "1" smd custom
			(at 0 -0.762 90)
			(size 0.2159 0.2159)
			(layers "F.Cu" "F.Mask" "F.Paste")
			(net "P12V")
			(options
				(clearance outline)
				(anchor circle)
			)
			(primitives
				(gr_poly
					(pts
						(arc
							(start -0.3302 -0.4318)
							(mid -0.402042 -0.402042)
							(end -0.4318 -0.3302)
						)
						(arc
							(start -0.4318 0.3302)
							(mid -0.402042 0.402042)
							(end -0.3302 0.4318)
						)
						(arc
							(start 0.3302 0.4318)
							(mid 0.402042 0.402042)
							(end 0.4318 0.3302)
						)
						(arc
							(start 0.4318 -0.3302)
							(mid 0.402042 -0.402042)
							(end 0.3302 -0.4318)
						)
					)
					(width 0)
					(fill yes)
				)
			)
		)
		(pad "2" smd custom
			(at 0 0.762 90)
			(size 0.2159 0.2159)
			(layers "F.Cu" "F.Mask" "F.Paste")
			(net "GND")
			(options
				(clearance outline)
				(anchor circle)
			)
			(primitives
				(gr_poly
					(pts
						(arc
							(start -0.3302 -0.4318)
							(mid -0.402042 -0.402042)
							(end -0.4318 -0.3302)
						)
						(arc
							(start -0.4318 0.3302)
							(mid -0.402042 0.402042)
							(end -0.3302 0.4318)
						)
						(arc
							(start 0.3302 0.4318)
							(mid 0.402042 0.402042)
							(end 0.4318 0.3302)
						)
						(arc
							(start 0.4318 -0.3302)
							(mid 0.402042 -0.402042)
							(end 0.3302 -0.4318)
						)
					)
					(width 0)
					(fill yes)
				)
			)
		)
	)
	(footprint ""
		(layer "F.Cu")
		(at 84.455 -205.994 90)
		(property "Reference" "R424"
			(at 0 0 90)
			(layer "F.SilkS")
			(hide yes)
			(effects
				(font
					(size 1.27 1.27)
				)
			)
		)
		(property "Value" "0R2J-2-GP"
			(at 0.064008 -3.993896 90)
			(unlocked yes)
			(layer "F.Fab")
			(hide yes)
			(effects
				(font
					(size 1.016 1.016)
					(thickness 0.1524)
				)
			)
		)
		(property "Device Type" "R402H16"
			(at 0.064008 -5.517896 90)
			(unlocked yes)
			(layer "F.Fab")
			(hide yes)
			(effects
				(font
					(size 1.016 1.016)
					(thickness 0.1524)
				)
			)
		)
		(duplicate_pad_numbers_are_jumpers no)
		(fp_line
			(start 0.508 -0.9398)
			(end -0.508 -0.9398)
			(stroke
				(width 0.1524)
				(type default)
			)
			(layer "F.SilkS")
		)
		(fp_line
			(start -0.508 -0.9398)
			(end -0.508 0.9398)
			(stroke
				(width 0.1524)
				(type default)
			)
			(layer "F.SilkS")
		)
		(fp_rect
			(start -0.508 0.9398)
			(end 0.508 -0.9398)
			(stroke
				(width 0)
				(type default)
			)
			(fill no)
			(layer "F.CrtYd")
		)
		(fp_rect
			(start -0.508 0.9398)
			(end 0.508 -0.9398)
			(stroke
				(width 0)
				(type default)
			)
			(fill no)
			(layer "F.Fab")
		)
		(pad "1" smd custom
			(at 0 -0.4445 90)
			(size 0.1397 0.1397)
			(layers "F.Cu" "F.Mask" "F.Paste")
			(net "BMC_I2C_SCL_BUF_8")
			(options
				(clearance outline)
				(anchor circle)
			)
			(primitives
				(gr_poly
					(pts
						(arc
							(start -0.1778 -0.2794)
							(mid -0.249642 -0.249642)
							(end -0.2794 -0.1778)
						)
						(arc
							(start -0.2794 0.1778)
							(mid -0.249642 0.249642)
							(end -0.1778 0.2794)
						)
						(arc
							(start 0.1778 0.2794)
							(mid 0.249642 0.249642)
							(end 0.2794 0.1778)
						)
						(arc
							(start 0.2794 -0.1778)
							(mid 0.249642 -0.249642)
							(end 0.1778 -0.2794)
						)
					)
					(width 0)
					(fill yes)
				)
			)
		)
		(pad "2" smd custom
			(at 0 0.4445 90)
			(size 0.1397 0.1397)
			(layers "F.Cu" "F.Mask" "F.Paste")
			(net "I2C_SCL_BUF_8_EU3_R")
			(options
				(clearance outline)
				(anchor circle)
			)
			(primitives
				(gr_poly
					(pts
						(arc
							(start -0.1778 -0.2794)
							(mid -0.249642 -0.249642)
							(end -0.2794 -0.1778)
						)
						(arc
							(start -0.2794 0.1778)
							(mid -0.249642 0.249642)
							(end -0.1778 0.2794)
						)
						(arc
							(start 0.1778 0.2794)
							(mid 0.249642 0.249642)
							(end 0.2794 0.1778)
						)
						(arc
							(start 0.2794 -0.1778)
							(mid 0.249642 -0.249642)
							(end 0.1778 -0.2794)
						)
					)
					(width 0)
					(fill yes)
				)
			)
		)
	)
)
